# BASEBOARD_FAB2 (Tioga Pass) — schematic netlist excerpt (pin names and nets, part order shuffled) for the footprints in the layout excerpt that follows; sources: Cadence DE-HDL packaged netlist, KiCad conversion of Wiwynn_Tioga_Pass_MB.brd

RN8F5  RES  33.2 1% CHIP  pkg 0402  page 246 : A = SPI_BMC_BT_DI ; B = SPI_TPM_BMC_DI_R
C25W97  CAP_A  0.1UF 16V 10% X7R  pkg 0402V  page 255 : A = P3V3_STBY ; B = GND
C3P32  CAP  0.22UF 16V 10% X7R  pkg 0402  page 107 : A = P3E_CPU0_PE1_SS_TXN<5> ; B = P3E_CPU0_PE1_PCH_TXN<5>

(kicad_pcb
	(version 20260206)
	(generator "pcbnew")
	(generator_version "10.0")
	(general
		(thickness 1.6)
		(legacy_teardrops no)
	)
	(paper "A4")
	(title_block
		(title "Wiwynn_Tioga_Pass_MB.brd")
		(comment 1 "Tioga Pass / footprints 4108-4110 of 4770")
	)
	(layers
		(0 "F.Cu" signal "TOP")
		(4 "In1.Cu" signal "L2GND")
		(6 "In2.Cu" signal "L3")
		(8 "In3.Cu" signal "L4GND")
		(10 "In4.Cu" signal "L5")
		(12 "In5.Cu" signal "L6GND")
		(14 "In6.Cu" signal "L7VCC")
		(16 "In7.Cu" signal "L8VCC")
		(18 "In8.Cu" signal "L9GND")
		(20 "In9.Cu" signal "L10")
		(22 "In10.Cu" signal "L11GND")
		(24 "In11.Cu" signal "L12")
		(26 "In12.Cu" signal "L13GND")
		(2 "B.Cu" signal "BOTTOM")
		(9 "F.Adhes" user "F.Adhesive")
		(11 "B.Adhes" user "B.Adhesive")
		(13 "F.Paste" user "Package Geometry/Pastemask Top")
		(15 "B.Paste" user "Package Geometry/Pastemask Bottom")
		(5 "F.SilkS" user "Ref Des/Silkscreen Top")
		(7 "B.SilkS" user "Ref Des/Silkscreen Bottom")
		(1 "F.Mask" user "Board Geometry/Soldermask Top")
		(3 "B.Mask" user "Board Geometry/Soldermask Bottom")
		(17 "Dwgs.User" user "User.Drawings")
		(19 "Cmts.User" user "User.Comments")
		(21 "Eco1.User" user "User.Eco1")
		(23 "Eco2.User" user "User.Eco2")
		(25 "Edge.Cuts" user "Board Geometry/Outline")
		(27 "Margin" user)
		(31 "F.CrtYd" user "Package Geometry/Place Bound Top")
		(29 "B.CrtYd" user "Package Geometry/Place Bound Bottom")
		(35 "F.Fab" user "Ref Des/Assembly Top")
		(33 "B.Fab" user "Ref Des/Assembly Bottom")
	)
	(footprint ""
		(layer "B.Cu")
		(at 442.663326 -147.663154 90)
		(property "Reference" "C25W97"
			(at 0.8382 -0.67818 90)
			(unlocked yes)
			(layer "B.SilkS")
			(effects
				(font
					(size 0.4064 0.254)
					(thickness 0.1524)
				)
				(justify left mirror)
			)
		)
		(property "Value" ""
			(at 0 0 90)
			(layer "B.Fab")
			(effects
				(font
					(size 1.27 1.27)
				)
				(justify mirror)
			)
		)
		(duplicate_pad_numbers_are_jumpers no)
		(fp_poly
			(pts
				(xy -0.3048 -0.1016) (xy -0.3048 0.9906) (xy 0.3048 0.9906) (xy 0.3048 -0.1016)
			)
			(stroke
				(width 0)
				(type default)
			)
			(fill no)
			(layer "B.CrtYd")
		)
		(fp_line
			(start 0.3048 -0.1016)
			(end 0.3048 0.9906)
			(stroke
				(width 0.1)
				(type default)
			)
			(layer "B.Fab")
		)
		(fp_line
			(start -0.3048 -0.1016)
			(end 0.3048 -0.1016)
			(stroke
				(width 0.1)
				(type default)
			)
			(layer "B.Fab")
		)
		(fp_line
			(start 0.3048 0.9906)
			(end -0.3048 0.9906)
			(stroke
				(width 0.1)
				(type default)
			)
			(layer "B.Fab")
		)
		(fp_line
			(start -0.3048 0.9906)
			(end -0.3048 -0.1016)
			(stroke
				(width 0.1)
				(type default)
			)
			(layer "B.Fab")
		)
		(pad "1" smd rect
			(at 0 0 270)
			(size 0.508 0.508)
			(layers "B.Cu" "B.Mask" "B.Paste")
			(net "P3V3_STBY")
		)
		(pad "2" smd rect
			(at 0 0.889 270)
			(size 0.508 0.508)
			(layers "B.Cu" "B.Mask" "B.Paste")
			(net "GND")
		)
		(zone
			(layer "B.Cu")
			(hatch none 0.5)
			(connect_pads
				(clearance 0)
			)
			(min_thickness 0.25)
			(keepout
				(tracks allowed)
				(vias not_allowed)
				(pads allowed)
				(copperpour not_allowed)
				(footprints allowed)
			)
			(placement
				(enabled no)
				(sheetname "")
			)
			(fill
				(thermal_gap 0.5)
				(thermal_bridge_width 0.5)
				(island_removal_mode 0)
			)
			(polygon
				(pts
					(xy 442.917326 -147.917154) (xy 442.917326 -147.409154) (xy 443.298326 -147.409154) (xy 443.298326 -147.917154)
				)
			)
		)
		(zone
			(layer "B.Cu")
			(hatch none 0.5)
			(connect_pads
				(clearance 0)
			)
			(min_thickness 0.25)
			(keepout
				(tracks not_allowed)
				(vias allowed)
				(pads allowed)
				(copperpour not_allowed)
				(footprints allowed)
			)
			(placement
				(enabled no)
				(sheetname "")
			)
			(fill
				(thermal_gap 0.5)
				(thermal_bridge_width 0.5)
				(island_removal_mode 0)
			)
			(polygon
				(pts
					(xy 443.298326 -147.917154) (xy 443.298326 -147.409154) (xy 442.917326 -147.409154) (xy 442.917326 -147.917154)
				)
			)
		)
	)
	(footprint ""
		(layer "B.Cu")
		(at 377.493022 -27.253438)
		(property "Reference" "RN8F5"
			(at 0.8382 -0.67818 0)
			(unlocked yes)
			(layer "B.SilkS")
			(effects
				(font
					(size 0.4064 0.254)
					(thickness 0.1524)
				)
				(justify left mirror)
			)
		)
		(property "Value" ""
			(at 0 0 0)
			(layer "B.Fab")
			(effects
				(font
					(size 1.27 1.27)
				)
				(justify mirror)
			)
		)
		(duplicate_pad_numbers_are_jumpers no)
		(fp_poly
			(pts
				(xy 0.2794 -0.1016) (xy -0.2794 -0.1016) (xy -0.2794 0.9906) (xy 0.2794 0.9906)
			)
			(stroke
				(width 0)
				(type default)
			)
			(fill no)
			(layer "B.CrtYd")
		)
		(fp_line
			(start -0.2794 -0.1016)
			(end 0.2794 -0.1016)
			(stroke
				(width 0.1)
				(type default)
			)
			(layer "B.Fab")
		)
		(fp_line
			(start -0.2794 0.9906)
			(end -0.2794 -0.1016)
			(stroke
				(width 0.1)
				(type default)
			)
			(layer "B.Fab")
		)
		(fp_line
			(start 0.2794 -0.1016)
			(end 0.2794 0.9906)
			(stroke
				(width 0.1)
				(type default)
			)
			(layer "B.Fab")
		)
		(fp_line
			(start 0.2794 0.9906)
			(end -0.2794 0.9906)
			(stroke
				(width 0.1)
				(type default)
			)
			(layer "B.Fab")
		)
		(pad "1" smd rect
			(at 0 0 180)
			(size 0.508 0.508)
			(layers "B.Cu" "B.Mask" "B.Paste")
			(net "SPI_BMC_BT_DI")
		)
		(pad "2" smd rect
			(at 0 0.889 180)
			(size 0.508 0.508)
			(layers "B.Cu" "B.Mask" "B.Paste")
			(net "SPI_TPM_BMC_DI_R")
		)
		(zone
			(layer "B.Cu")
			(hatch none 0.5)
			(connect_pads
				(clearance 0)
			)
			(min_thickness 0.25)
			(keepout
				(tracks allowed)
				(vias not_allowed)
				(pads allowed)
				(copperpour not_allowed)
				(footprints allowed)
			)
			(placement
				(enabled no)
				(sheetname "")
			)
			(fill
				(thermal_gap 0.5)
				(thermal_bridge_width 0.5)
				(island_removal_mode 0)
			)
			(polygon
				(pts
					(xy 377.747022 -26.999438) (xy 377.239022 -26.999438) (xy 377.239022 -26.618438) (xy 377.747022 -26.618438)
				)
			)
		)
		(zone
			(layer "B.Cu")
			(hatch none 0.5)
			(connect_pads
				(clearance 0)
			)
			(min_thickness 0.25)
			(keepout
				(tracks not_allowed)
				(vias allowed)
				(pads allowed)
				(copperpour not_allowed)
				(footprints allowed)
			)
			(placement
				(enabled no)
				(sheetname "")
			)
			(fill
				(thermal_gap 0.5)
				(thermal_bridge_width 0.5)
				(island_removal_mode 0)
			)
			(polygon
				(pts
					(xy 377.747022 -26.618438) (xy 377.239022 -26.618438) (xy 377.239022 -26.999438) (xy 377.747022 -26.999438)
				)
			)
		)
	)
	(footprint ""
		(layer "B.Cu")
		(at 354.36429 -77.915516 180)
		(property "Reference" "C3P32"
			(at 0 0 0)
			(layer "B.SilkS")
			(hide yes)
			(effects
				(font
					(size 1.27 1.27)
				)
				(justify mirror)
			)
		)
		(property "Value" ""
			(at 0 0 0)
			(layer "B.Fab")
			(effects
				(font
					(size 1.27 1.27)
				)
				(justify mirror)
			)
		)
		(duplicate_pad_numbers_are_jumpers no)
		(fp_poly
			(pts
				(xy -0.3048 -0.1016) (xy -0.3048 0.9906) (xy 0.3048 0.9906) (xy 0.3048 -0.1016)
			)
			(stroke
				(width 0)
				(type default)
			)
			(fill no)
			(layer "B.CrtYd")
		)
		(fp_line
			(start 0.3048 0.9906)
			(end -0.3048 0.9906)
			(stroke
				(width 0.1)
				(type default)
			)
			(layer "B.Fab")
		)
		(fp_line
			(start 0.3048 -0.1016)
			(end 0.3048 0.9906)
			(stroke
				(width 0.1)
				(type default)
			)
			(layer "B.Fab")
		)
		(fp_line
			(start -0.3048 0.9906)
			(end -0.3048 -0.1016)
			(stroke
				(width 0.1)
				(type default)
			)
			(layer "B.Fab")
		)
		(fp_line
			(start -0.3048 -0.1016)
			(end 0.3048 -0.1016)
			(stroke
				(width 0.1)
				(type default)
			)
			(layer "B.Fab")
		)
		(pad "1" smd rect
			(at 0 0)
			(size 0.508 0.508)
			(layers "B.Cu" "B.Mask" "B.Paste")
			(net "P3E_CPU0_PE1_SS_TXN<5>")
		)
		(pad "2" smd rect
			(at 0 0.889)
			(size 0.508 0.508)
			(layers "B.Cu" "B.Mask" "B.Paste")
			(net "P3E_CPU0_PE1_PCH_TXN<5>")
		)
		(zone
			(layer "B.Cu")
			(hatch none 0.5)
			(connect_pads
				(clearance 0)
			)
			(min_thickness 0.25)
			(keepout
				(tracks not_allowed)
				(vias allowed)
				(pads allowed)
				(copperpour not_allowed)
				(footprints allowed)
			)
			(placement
				(enabled no)
				(sheetname "")
			)
			(fill
				(thermal_gap 0.5)
				(thermal_bridge_width 0.5)
				(island_removal_mode 0)
			)
			(polygon
				(pts
					(xy 354.11029 -78.550516) (xy 354.61829 -78.550516) (xy 354.61829 -78.169516) (xy 354.11029 -78.169516)
				)
			)
		)
		(zone
			(layer "B.Cu")
			(hatch none 0.5)
			(connect_pads
				(clearance 0)
			)
			(min_thickness 0.25)
			(keepout
				(tracks allowed)
				(vias not_allowed)
				(pads allowed)
				(copperpour not_allowed)
				(footprints allowed)
			)
			(placement
				(enabled no)
				(sheetname "")
			)
			(fill
				(thermal_gap 0.5)
				(thermal_bridge_width 0.5)
				(island_removal_mode 0)
			)
			(polygon
				(pts
					(xy 354.11029 -78.169516) (xy 354.61829 -78.169516) (xy 354.61829 -78.550516) (xy 354.11029 -78.550516)
				)
			)
		)
	)
)
